(kicad_pcb
	(version 20260206)
	(generator "pcbnew")
	(generator_version "10.0")
	(general
		(thickness 1.6)
		(legacy_teardrops no)
	)
	(paper "A4")
	(title_block
		(title "Wiwynn_Tioga_Pass_MB.brd")
		(comment 1 "Tioga Pass / footprints 4417-4424 of 4770")
	)
	(layers
		(0 "F.Cu" signal "TOP")
		(4 "In1.Cu" signal "L2GND")
		(6 "In2.Cu" signal "L3")
		(8 "In3.Cu" signal "L4GND")
		(10 "In4.Cu" signal "L5")
		(12 "In5.Cu" signal "L6GND")
		(14 "In6.Cu" signal "L7VCC")
		(16 "In7.Cu" signal "L8VCC")
		(18 "In8.Cu" signal "L9GND")
		(20 "In9.Cu" signal "L10")
		(22 "In10.Cu" signal "L11GND")
		(24 "In11.Cu" signal "L12")
		(26 "In12.Cu" signal "L13GND")
		(2 "B.Cu" signal "BOTTOM")
		(9 "F.Adhes" user "F.Adhesive")
		(11 "B.Adhes" user "B.Adhesive")
		(13 "F.Paste" user "Package Geometry/Pastemask Top")
		(15 "B.Paste" user "Package Geometry/Pastemask Bottom")
		(5 "F.SilkS" user "Ref Des/Silkscreen Top")
		(7 "B.SilkS" user "Ref Des/Silkscreen Bottom")
		(1 "F.Mask" user "Board Geometry/Soldermask Top")
		(3 "B.Mask" user "Board Geometry/Soldermask Bottom")
		(17 "Dwgs.User" user "User.Drawings")
		(19 "Cmts.User" user "User.Comments")
		(21 "Eco1.User" user "User.Eco1")
		(23 "Eco2.User" user "User.Eco2")
		(25 "Edge.Cuts" user "Board Geometry/Outline")
		(27 "Margin" user)
		(31 "F.CrtYd" user "Package Geometry/Place Bound Top")
		(29 "B.CrtYd" user "Package Geometry/Place Bound Bottom")
		(35 "F.Fab" user "Ref Des/Assembly Top")
		(33 "B.Fab" user "Ref Des/Assembly Bottom")
	)
	(footprint ""
		(layer "B.Cu")
		(at 359.1052 -4.2418 180)
		(property "Reference" "R8W11"
			(at 0.8382 -0.67818 180)
			(unlocked yes)
			(layer "B.SilkS")
			(effects
				(font
					(size 0.4064 0.254)
					(thickness 0.1524)
				)
				(justify left mirror)
			)
		)
		(property "Value" ""
			(at 0 0 0)
			(layer "B.Fab")
			(effects
				(font
					(size 1.27 1.27)
				)
				(justify mirror)
			)
		)
		(duplicate_pad_numbers_are_jumpers no)
		(fp_poly
			(pts
				(xy 0.2794 -0.1016) (xy -0.2794 -0.1016) (xy -0.2794 0.9906) (xy 0.2794 0.9906)
			)
			(stroke
				(width 0)
				(type default)
			)
			(fill no)
			(layer "B.CrtYd")
		)
		(fp_line
			(start 0.2794 0.9906)
			(end -0.2794 0.9906)
			(stroke
				(width 0.1)
				(type default)
			)
			(layer "B.Fab")
		)
		(fp_line
			(start 0.2794 -0.1016)
			(end 0.2794 0.9906)
			(stroke
				(width 0.1)
				(type default)
			)
			(layer "B.Fab")
		)
		(fp_line
			(start -0.2794 0.9906)
			(end -0.2794 -0.1016)
			(stroke
				(width 0.1)
				(type default)
			)
			(layer "B.Fab")
		)
		(fp_line
			(start -0.2794 -0.1016)
			(end 0.2794 -0.1016)
			(stroke
				(width 0.1)
				(type default)
			)
			(layer "B.Fab")
		)
		(pad "1" smd rect
			(at 0 0)
			(size 0.508 0.508)
			(layers "B.Cu" "B.Mask" "B.Paste")
			(net "JTAG_RISER_TCK")
		)
		(pad "2" smd rect
			(at 0 0.889)
			(size 0.508 0.508)
			(layers "B.Cu" "B.Mask" "B.Paste")
			(net "JTAG_PLD_TCK_MUX")
		)
		(zone
			(layer "B.Cu")
			(hatch none 0.5)
			(connect_pads
				(clearance 0)
			)
			(min_thickness 0.25)
			(keepout
				(tracks not_allowed)
				(vias allowed)
				(pads allowed)
				(copperpour not_allowed)
				(footprints allowed)
			)
			(placement
				(enabled no)
				(sheetname "")
			)
			(fill
				(thermal_gap 0.5)
				(thermal_bridge_width 0.5)
				(island_removal_mode 0)
			)
			(polygon
				(pts
					(xy 358.8512 -4.8768) (xy 359.3592 -4.8768) (xy 359.3592 -4.4958) (xy 358.8512 -4.4958)
				)
			)
		)
		(zone
			(layer "B.Cu")
			(hatch none 0.5)
			(connect_pads
				(clearance 0)
			)
			(min_thickness 0.25)
			(keepout
				(tracks allowed)
				(vias not_allowed)
				(pads allowed)
				(copperpour not_allowed)
				(footprints allowed)
			)
			(placement
				(enabled no)
				(sheetname "")
			)
			(fill
				(thermal_gap 0.5)
				(thermal_bridge_width 0.5)
				(island_removal_mode 0)
			)
			(polygon
				(pts
					(xy 358.8512 -4.4958) (xy 359.3592 -4.4958) (xy 359.3592 -4.8768) (xy 358.8512 -4.8768)
				)
			)
		)
	)
	(footprint ""
		(layer "B.Cu")
		(at 29.563568 -155.448)
		(property "Reference" "R9L1"
			(at 0 0 0)
			(layer "B.SilkS")
			(hide yes)
			(effects
				(font
					(size 1.27 1.27)
				)
				(justify mirror)
			)
		)
		(property "Value" ""
			(at 0 0 0)
			(layer "B.Fab")
			(effects
				(font
					(size 1.27 1.27)
				)
				(justify mirror)
			)
		)
		(duplicate_pad_numbers_are_jumpers no)
		(fp_poly
			(pts
				(xy 0.2794 -0.1016) (xy -0.2794 -0.1016) (xy -0.2794 0.9906) (xy 0.2794 0.9906)
			)
			(stroke
				(width 0)
				(type default)
			)
			(fill no)
			(layer "B.CrtYd")
		)
		(fp_line
			(start -0.2794 -0.1016)
			(end 0.2794 -0.1016)
			(stroke
				(width 0.1)
				(type default)
			)
			(layer "B.Fab")
		)
		(fp_line
			(start -0.2794 0.9906)
			(end -0.2794 -0.1016)
			(stroke
				(width 0.1)
				(type default)
			)
			(layer "B.Fab")
		)
		(fp_line
			(start 0.2794 -0.1016)
			(end 0.2794 0.9906)
			(stroke
				(width 0.1)
				(type default)
			)
			(layer "B.Fab")
		)
		(fp_line
			(start 0.2794 0.9906)
			(end -0.2794 0.9906)
			(stroke
				(width 0.1)
				(type default)
			)
			(layer "B.Fab")
		)
		(pad "1" smd rect
			(at 0 0 180)
			(size 0.508 0.508)
			(layers "B.Cu" "B.Mask" "B.Paste")
			(net "M_M_VREF")
		)
		(pad "2" smd rect
			(at 0 0.889 180)
			(size 0.508 0.508)
			(layers "B.Cu" "B.Mask" "B.Paste")
			(net "GND")
		)
		(zone
			(layer "B.Cu")
			(hatch none 0.5)
			(connect_pads
				(clearance 0)
			)
			(min_thickness 0.25)
			(keepout
				(tracks allowed)
				(vias not_allowed)
				(pads allowed)
				(copperpour not_allowed)
				(footprints allowed)
			)
			(placement
				(enabled no)
				(sheetname "")
			)
			(fill
				(thermal_gap 0.5)
				(thermal_bridge_width 0.5)
				(island_removal_mode 0)
			)
			(polygon
				(pts
					(xy 29.817568 -155.194) (xy 29.309568 -155.194) (xy 29.309568 -154.813) (xy 29.817568 -154.813)
				)
			)
		)
		(zone
			(layer "B.Cu")
			(hatch none 0.5)
			(connect_pads
				(clearance 0)
			)
			(min_thickness 0.25)
			(keepout
				(tracks not_allowed)
				(vias allowed)
				(pads allowed)
				(copperpour not_allowed)
				(footprints allowed)
			)
			(placement
				(enabled no)
				(sheetname "")
			)
			(fill
				(thermal_gap 0.5)
				(thermal_bridge_width 0.5)
				(island_removal_mode 0)
			)
			(polygon
				(pts
					(xy 29.817568 -154.813) (xy 29.309568 -154.813) (xy 29.309568 -155.194) (xy 29.817568 -155.194)
				)
			)
		)
	)
	(footprint ""
		(layer "B.Cu")
		(at 402.336 -87.3125 180)
		(property "Reference" "R8D44"
			(at 0.8382 -0.67818 180)
			(unlocked yes)
			(layer "B.SilkS")
			(effects
				(font
					(size 0.4064 0.254)
					(thickness 0.1524)
				)
				(justify left mirror)
			)
		)
		(property "Value" ""
			(at 0 0 0)
			(layer "B.Fab")
			(effects
				(font
					(size 1.27 1.27)
				)
				(justify mirror)
			)
		)
		(duplicate_pad_numbers_are_jumpers no)
		(fp_poly
			(pts
				(xy 0.2794 -0.1016) (xy -0.2794 -0.1016) (xy -0.2794 0.9906) (xy 0.2794 0.9906)
			)
			(stroke
				(width 0)
				(type default)
			)
			(fill no)
			(layer "B.CrtYd")
		)
		(fp_line
			(start 0.2794 0.9906)
			(end -0.2794 0.9906)
			(stroke
				(width 0.1)
				(type default)
			)
			(layer "B.Fab")
		)
		(fp_line
			(start 0.2794 -0.1016)
			(end 0.2794 0.9906)
			(stroke
				(width 0.1)
				(type default)
			)
			(layer "B.Fab")
		)
		(fp_line
			(start -0.2794 0.9906)
			(end -0.2794 -0.1016)
			(stroke
				(width 0.1)
				(type default)
			)
			(layer "B.Fab")
		)
		(fp_line
			(start -0.2794 -0.1016)
			(end 0.2794 -0.1016)
			(stroke
				(width 0.1)
				(type default)
			)
			(layer "B.Fab")
		)
		(pad "1" smd rect
			(at 0 0)
			(size 0.508 0.508)
			(layers "B.Cu" "B.Mask" "B.Paste")
			(net "P3V3_STBY")
		)
		(pad "2" smd rect
			(at 0 0.889)
			(size 0.508 0.508)
			(layers "B.Cu" "B.Mask" "B.Paste")
			(net "FM_CPU0_RC_EN")
		)
		(zone
			(layer "B.Cu")
			(hatch none 0.5)
			(connect_pads
				(clearance 0)
			)
			(min_thickness 0.25)
			(keepout
				(tracks not_allowed)
				(vias allowed)
				(pads allowed)
				(copperpour not_allowed)
				(footprints allowed)
			)
			(placement
				(enabled no)
				(sheetname "")
			)
			(fill
				(thermal_gap 0.5)
				(thermal_bridge_width 0.5)
				(island_removal_mode 0)
			)
			(polygon
				(pts
					(xy 402.082 -87.9475) (xy 402.59 -87.9475) (xy 402.59 -87.5665) (xy 402.082 -87.5665)
				)
			)
		)
		(zone
			(layer "B.Cu")
			(hatch none 0.5)
			(connect_pads
				(clearance 0)
			)
			(min_thickness 0.25)
			(keepout
				(tracks allowed)
				(vias not_allowed)
				(pads allowed)
				(copperpour not_allowed)
				(footprints allowed)
			)
			(placement
				(enabled no)
				(sheetname "")
			)
			(fill
				(thermal_gap 0.5)
				(thermal_bridge_width 0.5)
				(island_removal_mode 0)
			)
			(polygon
				(pts
					(xy 402.082 -87.5665) (xy 402.59 -87.5665) (xy 402.59 -87.9475) (xy 402.082 -87.9475)
				)
			)
		)
	)
	(footprint ""
		(layer "B.Cu")
		(at 348.488 -104.267 180)
		(property "Reference" "C22W30"
			(at 0 0 0)
			(layer "B.SilkS")
			(hide yes)
			(effects
				(font
					(size 1.27 1.27)
				)
				(justify mirror)
			)
		)
		(property "Value" "*"
			(at 0.0762 -6.2357 180)
			(unlocked yes)
			(layer "B.Fab")
			(hide yes)
			(effects
				(font
					(size 1.27 1.016)
					(thickness 0.1524)
				)
				(justify mirror)
			)
		)
		(property "Device Type" "SC22U16V5MX-4-GP_SMD-BCG5-SC22A"
			(at 0.0762 -8.2677 180)
			(unlocked yes)
			(layer "B.Fab")
			(hide yes)
			(effects
				(font
					(size 1.27 1.016)
					(thickness 0.1524)
				)
				(justify mirror)
			)
		)
		(duplicate_pad_numbers_are_jumpers no)
		(fp_line
			(start -0.635 0)
			(end 0.635 0)
			(stroke
				(width 0.508)
				(type default)
			)
			(layer "B.SilkS")
		)
		(fp_rect
			(start 0.9652 1.778)
			(end -0.9652 -1.778)
			(stroke
				(width 0)
				(type default)
			)
			(fill no)
			(layer "B.CrtYd")
		)
		(fp_poly
			(pts
				(xy 0.9652 -1.778) (xy -0.9652 -1.778) (xy -0.9652 1.778) (xy 0.9652 1.778)
			)
			(stroke
				(width 0)
				(type default)
			)
			(fill no)
			(layer "B.Fab")
		)
		(pad "1" smd rect
			(at 0 -0.9652)
			(size 1.397 1.143)
			(layers "B.Cu" "B.Mask" "B.Paste")
			(net "VR_FET_SW_P12V_STBY_PVCCIO_CPU0")
		)
		(pad "2" smd rect
			(at 0 0.9652)
			(size 1.397 1.143)
			(layers "B.Cu" "B.Mask" "B.Paste")
			(net "GND")
		)
	)
	(footprint ""
		(layer "B.Cu")
		(at 436.547006 -43.54195 180)
		(property "Reference" "R25W43"
			(at 0 0 0)
			(layer "B.SilkS")
			(hide yes)
			(effects
				(font
					(size 1.27 1.27)
				)
				(justify mirror)
			)
		)
		(property "Value" "*"
			(at -0.064008 -4.108196 180)
			(unlocked yes)
			(layer "B.Fab")
			(hide yes)
			(effects
				(font
					(size 1.27 1.016)
					(thickness 0.1524)
				)
				(justify mirror)
			)
		)
		(property "Device Type" "120R2F-GP_RCL_GP-120R2F-GP,64.A"
			(at -0.064008 -5.632196 180)
			(unlocked yes)
			(layer "B.Fab")
			(hide yes)
			(effects
				(font
					(size 1.27 1.016)
					(thickness 0.1524)
				)
				(justify mirror)
			)
		)
		(duplicate_pad_numbers_are_jumpers no)
		(fp_line
			(start 0.508 -0.9398)
			(end 0.508 0.9398)
			(stroke
				(width 0.1524)
				(type default)
			)
			(layer "B.SilkS")
		)
		(fp_line
			(start -0.508 -0.9398)
			(end 0.508 -0.9398)
			(stroke
				(width 0.1524)
				(type default)
			)
			(layer "B.SilkS")
		)
		(fp_rect
			(start 0.508 0.9398)
			(end -0.508 -0.9398)
			(stroke
				(width 0)
				(type default)
			)
			(fill no)
			(layer "B.CrtYd")
		)
		(fp_rect
			(start 0.508 0.9398)
			(end -0.508 -0.9398)
			(stroke
				(width 0)
				(type default)
			)
			(fill no)
			(layer "B.Fab")
		)
		(pad "1" smd custom
			(at 0 -0.4445)
			(size 0.1397 0.1397)
			(layers "B.Cu" "B.Mask" "B.Paste")
			(net "BMC_M_A5")
			(options
				(clearance outline)
				(anchor circle)
			)
			(primitives
				(gr_poly
					(pts
						(arc
							(start -0.1778 0.2794)
							(mid -0.249642 0.249642)
							(end -0.2794 0.1778)
						)
						(arc
							(start -0.2794 -0.1778)
							(mid -0.249642 -0.249642)
							(end -0.1778 -0.2794)
						)
						(arc
							(start 0.1778 -0.2794)
							(mid 0.249642 -0.249642)
							(end 0.2794 -0.1778)
						)
						(arc
							(start 0.2794 0.1778)
							(mid 0.249642 0.249642)
							(end 0.1778 0.2794)
						)
					)
					(width 0)
					(fill yes)
				)
			)
		)
		(pad "2" smd custom
			(at 0 0.4445)
			(size 0.1397 0.1397)
			(layers "B.Cu" "B.Mask" "B.Paste")
			(net "P1V2_AUX_BMC")
			(options
				(clearance outline)
				(anchor circle)
			)
			(primitives
				(gr_poly
					(pts
						(arc
							(start -0.1778 0.2794)
							(mid -0.249642 0.249642)
							(end -0.2794 0.1778)
						)
						(arc
							(start -0.2794 -0.1778)
							(mid -0.249642 -0.249642)
							(end -0.1778 -0.2794)
						)
						(arc
							(start 0.1778 -0.2794)
							(mid 0.249642 -0.249642)
							(end 0.2794 -0.1778)
						)
						(arc
							(start 0.2794 0.1778)
							(mid 0.249642 0.249642)
							(end 0.1778 0.2794)
						)
					)
					(width 0)
					(fill yes)
				)
			)
		)
	)
	(footprint ""
		(layer "B.Cu")
		(at 495.01552 -133.6675 90)
		(property "Reference" "U1M2"
			(at -3.14198 -1.37541 270)
			(unlocked yes)
			(layer "B.SilkS")
			(effects
				(font
					(size 0.7874 0.5842)
					(thickness 0.1524)
				)
				(justify left mirror)
			)
		)
		(property "Value" ""
			(at 0 0 90)
			(layer "B.Fab")
			(effects
				(font
					(size 1.27 1.27)
				)
				(justify mirror)
			)
		)
		(duplicate_pad_numbers_are_jumpers no)
		(fp_circle
			(center 0.595884 -0.655574)
			(end 0.595884 -0.528574)
			(stroke
				(width 0.254)
				(type default)
			)
			(fill no)
			(layer "B.SilkS")
		)
		(fp_poly
			(pts
				(xy -0.21463 -0.450088) (xy -1.56337 -0.450088) (xy -1.56337 1.75006) (xy -0.21463 1.75006)
			)
			(stroke
				(width 0)
				(type default)
			)
			(fill no)
			(layer "B.CrtYd")
		)
		(fp_line
			(start -0.21463 -0.450088)
			(end -1.56337 -0.450088)
			(stroke
				(width 0.1)
				(type default)
			)
			(layer "B.Fab")
		)
		(fp_line
			(start -1.56337 -0.450088)
			(end -1.56337 1.75006)
			(stroke
				(width 0.1)
				(type default)
			)
			(layer "B.Fab")
		)
		(fp_line
			(start -0.21463 1.75006)
			(end -0.21463 -0.450088)
			(stroke
				(width 0.1)
				(type default)
			)
			(layer "B.Fab")
		)
		(fp_line
			(start -1.56337 1.75006)
			(end -0.21463 1.75006)
			(stroke
				(width 0.1)
				(type default)
			)
			(layer "B.Fab")
		)
		(fp_circle
			(center 0.848614 -0.6477)
			(end 0.848614 -0.5207)
			(stroke
				(width 0.254)
				(type default)
			)
			(fill no)
			(layer "B.Fab")
		)
		(pad "1" smd rect
			(at 0 0 270)
			(size 1.016 0.381)
			(layers "B.Cu" "B.Mask" "B.Paste")
			(net "JTAG_MCP_CPU0_TDO")
		)
		(pad "2" smd rect
			(at 0 0.649986 270)
			(size 1.016 0.381)
			(layers "B.Cu" "B.Mask" "B.Paste")
			(net "GND")
		)
		(pad "3" smd rect
			(at 0 1.299972 270)
			(size 1.016 0.381)
			(layers "B.Cu" "B.Mask" "B.Paste")
			(net "JTAG_MCP_CPU1_TDO")
		)
		(pad "4" smd rect
			(at -1.778 1.299972 270)
			(size 1.016 0.381)
			(layers "B.Cu" "B.Mask" "B.Paste")
			(net "JTAG_MCP_MUX_TDO")
		)
		(pad "5" smd rect
			(at -1.778 0.649986 270)
			(size 1.016 0.381)
			(layers "B.Cu" "B.Mask" "B.Paste")
			(net "P3V3_STBY")
		)
		(pad "6" smd rect
			(at -1.778 0 270)
			(size 1.016 0.381)
			(layers "B.Cu" "B.Mask" "B.Paste")
			(net "FM_CPU1_CD_PRES_N")
		)
	)
	(footprint ""
		(layer "B.Cu")
		(at 100.672392 -85.075014)
		(property "Reference" "C8P2"
			(at 0 0 0)
			(layer "B.SilkS")
			(hide yes)
			(effects
				(font
					(size 1.27 1.27)
				)
				(justify mirror)
			)
		)
		(property "Value" ""
			(at 0 0 0)
			(layer "B.Fab")
			(effects
				(font
					(size 1.27 1.27)
				)
				(justify mirror)
			)
		)
		(duplicate_pad_numbers_are_jumpers no)
		(fp_poly
			(pts
				(xy 0.7239 -0.2159) (xy -0.7239 -0.2159) (xy -0.7239 1.9939) (xy 0.7239 1.9939)
			)
			(stroke
				(width 0)
				(type default)
			)
			(fill no)
			(layer "B.CrtYd")
		)
		(fp_line
			(start -0.7239 -0.2159)
			(end 0.7239 -0.2159)
			(stroke
				(width 0.1)
				(type default)
			)
			(layer "B.Fab")
		)
		(fp_line
			(start -0.7239 1.9939)
			(end -0.7239 -0.2159)
			(stroke
				(width 0.1)
				(type default)
			)
			(layer "B.Fab")
		)
		(fp_line
			(start 0.7239 -0.2159)
			(end 0.7239 1.9939)
			(stroke
				(width 0.1)
				(type default)
			)
			(layer "B.Fab")
		)
		(fp_line
			(start 0.7239 1.9939)
			(end -0.7239 1.9939)
			(stroke
				(width 0.1)
				(type default)
			)
			(layer "B.Fab")
		)
		(pad "1" smd rect
			(at 0 0 180)
			(size 1.27 1.016)
			(layers "B.Cu" "B.Mask" "B.Paste")
			(net "PVDDQ_KLM")
		)
		(pad "2" smd rect
			(at 0 1.778 180)
			(size 1.27 1.016)
			(layers "B.Cu" "B.Mask" "B.Paste")
			(net "GND")
		)
		(zone
			(layer "B.Cu")
			(hatch none 0.5)
			(connect_pads
				(clearance 0)
			)
			(min_thickness 0.25)
			(keepout
				(tracks not_allowed)
				(vias allowed)
				(pads allowed)
				(copperpour not_allowed)
				(footprints allowed)
			)
			(placement
				(enabled no)
				(sheetname "")
			)
			(fill
				(thermal_gap 0.5)
				(thermal_bridge_width 0.5)
				(island_removal_mode 0)
			)
			(polygon
				(pts
					(xy 101.307392 -84.567014) (xy 100.037392 -84.567014) (xy 100.037392 -83.805014) (xy 101.307392 -83.805014)
				)
			)
		)
	)
	(footprint ""
		(layer "B.Cu")
		(at 195.453 1.524 90)
		(property "Reference" "C6U17"
			(at 0 0 90)
			(layer "B.SilkS")
			(hide yes)
			(effects
				(font
					(size 1.27 1.27)
				)
				(justify mirror)
			)
		)
		(property "Value" ""
			(at 0 0 90)
			(layer "B.Fab")
			(effects
				(font
					(size 1.27 1.27)
				)
				(justify mirror)
			)
		)
		(duplicate_pad_numbers_are_jumpers no)
		(fp_poly
			(pts
				(xy -0.3048 -0.1016) (xy -0.3048 0.9906) (xy 0.3048 0.9906) (xy 0.3048 -0.1016)
			)
			(stroke
				(width 0)
				(type default)
			)
			(fill no)
			(layer "B.CrtYd")
		)
		(fp_line
			(start 0.3048 -0.1016)
			(end 0.3048 0.9906)
			(stroke
				(width 0.1)
				(type default)
			)
			(layer "B.Fab")
		)
		(fp_line
			(start -0.3048 -0.1016)
			(end 0.3048 -0.1016)
			(stroke
				(width 0.1)
				(type default)
			)
			(layer "B.Fab")
		)
		(fp_line
			(start 0.3048 0.9906)
			(end -0.3048 0.9906)
			(stroke
				(width 0.1)
				(type default)
			)
			(layer "B.Fab")
		)
		(fp_line
			(start -0.3048 0.9906)
			(end -0.3048 -0.1016)
			(stroke
				(width 0.1)
				(type default)
			)
			(layer "B.Fab")
		)
		(pad "1" smd rect
			(at 0 0 270)
			(size 0.508 0.508)
			(layers "B.Cu" "B.Mask" "B.Paste")
			(net "M_C_VREF")
		)
		(pad "2" smd rect
			(at 0 0.889 270)
			(size 0.508 0.508)
			(layers "B.Cu" "B.Mask" "B.Paste")
			(net "GND")
		)
		(zone
			(layer "B.Cu")
			(hatch none 0.5)
			(connect_pads
				(clearance 0)
			)
			(min_thickness 0.25)
			(keepout
				(tracks allowed)
				(vias not_allowed)
				(pads allowed)
				(copperpour not_allowed)
				(footprints allowed)
			)
			(placement
				(enabled no)
				(sheetname "")
			)
			(fill
				(thermal_gap 0.5)
				(thermal_bridge_width 0.5)
				(island_removal_mode 0)
			)
			(polygon
				(pts
					(xy 195.707 1.27) (xy 195.707 1.778) (xy 196.088 1.778) (xy 196.088 1.27)
				)
			)
		)
		(zone
			(layer "B.Cu")
			(hatch none 0.5)
			(connect_pads
				(clearance 0)
			)
			(min_thickness 0.25)
			(keepout
				(tracks not_allowed)
				(vias allowed)
				(pads allowed)
				(copperpour not_allowed)
				(footprints allowed)
			)
			(placement
				(enabled no)
				(sheetname "")
			)
			(fill
				(thermal_gap 0.5)
				(thermal_bridge_width 0.5)
				(island_removal_mode 0)
			)
			(polygon
				(pts
					(xy 196.088 1.27) (xy 196.088 1.778) (xy 195.707 1.778) (xy 195.707 1.27)
				)
			)
		)
	)
)
